(kicad_pcb
	(version 20260206)
	(generator "pcbnew")
	(generator_version "10.0")
	(general
		(thickness 1.6)
		(legacy_teardrops no)
	)
	(paper "A4")
	(title_block
		(title "Wiwynn_Tioga_Pass_MB.brd")
		(comment 1 "Tioga Pass / footprints 65-73 of 4770")
	)
	(layers
		(0 "F.Cu" signal "TOP")
		(4 "In1.Cu" signal "L2GND")
		(6 "In2.Cu" signal "L3")
		(8 "In3.Cu" signal "L4GND")
		(10 "In4.Cu" signal "L5")
		(12 "In5.Cu" signal "L6GND")
		(14 "In6.Cu" signal "L7VCC")
		(16 "In7.Cu" signal "L8VCC")
		(18 "In8.Cu" signal "L9GND")
		(20 "In9.Cu" signal "L10")
		(22 "In10.Cu" signal "L11GND")
		(24 "In11.Cu" signal "L12")
		(26 "In12.Cu" signal "L13GND")
		(2 "B.Cu" signal "BOTTOM")
		(9 "F.Adhes" user "F.Adhesive")
		(11 "B.Adhes" user "B.Adhesive")
		(13 "F.Paste" user "Package Geometry/Pastemask Top")
		(15 "B.Paste" user "Package Geometry/Pastemask Bottom")
		(5 "F.SilkS" user "Ref Des/Silkscreen Top")
		(7 "B.SilkS" user "Ref Des/Silkscreen Bottom")
		(1 "F.Mask" user "Board Geometry/Soldermask Top")
		(3 "B.Mask" user "Board Geometry/Soldermask Bottom")
		(17 "Dwgs.User" user "User.Drawings")
		(19 "Cmts.User" user "User.Comments")
		(21 "Eco1.User" user "User.Eco1")
		(23 "Eco2.User" user "User.Eco2")
		(25 "Edge.Cuts" user "Board Geometry/Outline")
		(27 "Margin" user)
		(31 "F.CrtYd" user "Package Geometry/Place Bound Top")
		(29 "B.CrtYd" user "Package Geometry/Place Bound Bottom")
		(35 "F.Fab" user "Ref Des/Assembly Top")
		(33 "B.Fab" user "Ref Des/Assembly Bottom")
	)
	(footprint ""
		(layer "F.Cu")
		(at 261.9502 -79.6036 180)
		(property "Reference" "C5D14"
			(at 0 0 180)
			(layer "F.SilkS")
			(hide yes)
			(effects
				(font
					(size 1.27 1.27)
				)
			)
		)
		(property "Value" ""
			(at 0 0 180)
			(layer "F.Fab")
			(effects
				(font
					(size 1.27 1.27)
				)
			)
		)
		(duplicate_pad_numbers_are_jumpers no)
		(fp_poly
			(pts
				(xy -0.4953 -0.2032) (xy 0.4953 -0.2032) (xy 0.4953 1.6002) (xy -0.4953 1.6002)
			)
			(stroke
				(width 0)
				(type default)
			)
			(fill no)
			(layer "F.CrtYd")
		)
		(fp_line
			(start 0.4953 1.6002)
			(end -0.4953 1.6002)
			(stroke
				(width 0.1)
				(type default)
			)
			(layer "F.Fab")
		)
		(fp_line
			(start 0.4953 -0.2032)
			(end 0.4953 1.6002)
			(stroke
				(width 0.1)
				(type default)
			)
			(layer "F.Fab")
		)
		(fp_line
			(start -0.4953 1.6002)
			(end -0.4953 -0.2032)
			(stroke
				(width 0.1)
				(type default)
			)
			(layer "F.Fab")
		)
		(fp_line
			(start -0.4953 -0.2032)
			(end 0.4953 -0.2032)
			(stroke
				(width 0.1)
				(type default)
			)
			(layer "F.Fab")
		)
		(pad "1" smd rect
			(at 0 0 180)
			(size 0.762 0.889)
			(layers "F.Cu" "F.Mask" "F.Paste")
			(net "PVCCIN_CPU0")
		)
		(pad "2" smd rect
			(at 0 1.397 180)
			(size 0.762 0.889)
			(layers "F.Cu" "F.Mask" "F.Paste")
			(net "GND")
		)
		(zone
			(layer "F.Cu")
			(hatch none 0.5)
			(connect_pads
				(clearance 0)
			)
			(min_thickness 0.25)
			(keepout
				(tracks not_allowed)
				(vias allowed)
				(pads allowed)
				(copperpour not_allowed)
				(footprints allowed)
			)
			(placement
				(enabled no)
				(sheetname "")
			)
			(fill
				(thermal_gap 0.5)
				(thermal_bridge_width 0.5)
				(island_removal_mode 0)
			)
			(polygon
				(pts
					(xy 262.3312 -80.0481) (xy 261.5692 -80.0481) (xy 261.5692 -80.5561) (xy 262.3312 -80.5561)
				)
			)
		)
	)
	(footprint ""
		(layer "F.Cu")
		(at 96.94164 -73.318116)
		(property "Reference" "C2D33"
			(at 0 0 0)
			(layer "F.SilkS")
			(hide yes)
			(effects
				(font
					(size 1.27 1.27)
				)
			)
		)
		(property "Value" ""
			(at 0 0 0)
			(layer "F.Fab")
			(effects
				(font
					(size 1.27 1.27)
				)
			)
		)
		(duplicate_pad_numbers_are_jumpers no)
		(fp_poly
			(pts
				(xy -0.4953 -0.2032) (xy 0.4953 -0.2032) (xy 0.4953 1.6002) (xy -0.4953 1.6002)
			)
			(stroke
				(width 0)
				(type default)
			)
			(fill no)
			(layer "F.CrtYd")
		)
		(fp_line
			(start -0.4953 -0.2032)
			(end 0.4953 -0.2032)
			(stroke
				(width 0.1)
				(type default)
			)
			(layer "F.Fab")
		)
		(fp_line
			(start -0.4953 1.6002)
			(end -0.4953 -0.2032)
			(stroke
				(width 0.1)
				(type default)
			)
			(layer "F.Fab")
		)
		(fp_line
			(start 0.4953 -0.2032)
			(end 0.4953 1.6002)
			(stroke
				(width 0.1)
				(type default)
			)
			(layer "F.Fab")
		)
		(fp_line
			(start 0.4953 1.6002)
			(end -0.4953 1.6002)
			(stroke
				(width 0.1)
				(type default)
			)
			(layer "F.Fab")
		)
		(pad "1" smd rect
			(at 0 0)
			(size 0.762 0.889)
			(layers "F.Cu" "F.Mask" "F.Paste")
			(net "PVCCIN_CPU1")
		)
		(pad "2" smd rect
			(at 0 1.397)
			(size 0.762 0.889)
			(layers "F.Cu" "F.Mask" "F.Paste")
			(net "GND")
		)
		(zone
			(layer "F.Cu")
			(hatch none 0.5)
			(connect_pads
				(clearance 0)
			)
			(min_thickness 0.25)
			(keepout
				(tracks not_allowed)
				(vias allowed)
				(pads allowed)
				(copperpour not_allowed)
				(footprints allowed)
			)
			(placement
				(enabled no)
				(sheetname "")
			)
			(fill
				(thermal_gap 0.5)
				(thermal_bridge_width 0.5)
				(island_removal_mode 0)
			)
			(polygon
				(pts
					(xy 96.56064 -72.873616) (xy 97.32264 -72.873616) (xy 97.32264 -72.365616) (xy 96.56064 -72.365616)
				)
			)
		)
	)
	(footprint ""
		(layer "F.Cu")
		(at 193.675 -23.396194)
		(property "Reference" "R4F4"
			(at 0 0 0)
			(layer "F.SilkS")
			(hide yes)
			(effects
				(font
					(size 1.27 1.27)
				)
			)
		)
		(property "Value" ""
			(at 0 0 0)
			(layer "F.Fab")
			(effects
				(font
					(size 1.27 1.27)
				)
			)
		)
		(duplicate_pad_numbers_are_jumpers no)
		(fp_poly
			(pts
				(xy -0.2794 -0.1016) (xy 0.2794 -0.1016) (xy 0.2794 0.9906) (xy -0.2794 0.9906)
			)
			(stroke
				(width 0)
				(type default)
			)
			(fill no)
			(layer "F.CrtYd")
		)
		(fp_line
			(start -0.2794 -0.1016)
			(end -0.2794 0.9906)
			(stroke
				(width 0.1)
				(type default)
			)
			(layer "F.Fab")
		)
		(fp_line
			(start -0.2794 0.9906)
			(end 0.2794 0.9906)
			(stroke
				(width 0.1)
				(type default)
			)
			(layer "F.Fab")
		)
		(fp_line
			(start 0.2794 -0.1016)
			(end -0.2794 -0.1016)
			(stroke
				(width 0.1)
				(type default)
			)
			(layer "F.Fab")
		)
		(fp_line
			(start 0.2794 0.9906)
			(end 0.2794 -0.1016)
			(stroke
				(width 0.1)
				(type default)
			)
			(layer "F.Fab")
		)
		(pad "1" smd rect
			(at 0 0)
			(size 0.508 0.508)
			(layers "F.Cu" "F.Mask" "F.Paste")
			(net "PVDDQ_ABC")
		)
		(pad "2" smd rect
			(at 0 0.889)
			(size 0.508 0.508)
			(layers "F.Cu" "F.Mask" "F.Paste")
			(net "M_A_VREF")
		)
		(zone
			(layer "F.Cu")
			(hatch none 0.5)
			(connect_pads
				(clearance 0)
			)
			(min_thickness 0.25)
			(keepout
				(tracks allowed)
				(vias not_allowed)
				(pads allowed)
				(copperpour not_allowed)
				(footprints allowed)
			)
			(placement
				(enabled no)
				(sheetname "")
			)
			(fill
				(thermal_gap 0.5)
				(thermal_bridge_width 0.5)
				(island_removal_mode 0)
			)
			(polygon
				(pts
					(xy 193.421 -23.142194) (xy 193.929 -23.142194) (xy 193.929 -22.761194) (xy 193.421 -22.761194)
				)
			)
		)
		(zone
			(layer "F.Cu")
			(hatch none 0.5)
			(connect_pads
				(clearance 0)
			)
			(min_thickness 0.25)
			(keepout
				(tracks not_allowed)
				(vias allowed)
				(pads allowed)
				(copperpour not_allowed)
				(footprints allowed)
			)
			(placement
				(enabled no)
				(sheetname "")
			)
			(fill
				(thermal_gap 0.5)
				(thermal_bridge_width 0.5)
				(island_removal_mode 0)
			)
			(polygon
				(pts
					(xy 193.421 -22.761194) (xy 193.929 -22.761194) (xy 193.929 -23.142194) (xy 193.421 -23.142194)
				)
			)
		)
	)
	(footprint ""
		(layer "F.Cu")
		(at 386.2451 -68.8848 180)
		(property "Reference" "C7E13"
			(at 0 0 180)
			(layer "F.SilkS")
			(hide yes)
			(effects
				(font
					(size 1.27 1.27)
				)
			)
		)
		(property "Value" "*"
			(at -0.0762 -6.2357 180)
			(unlocked yes)
			(layer "F.Fab")
			(hide yes)
			(effects
				(font
					(size 1.27 1.016)
					(thickness 0.1524)
				)
			)
		)
		(property "Device Type" "SC22U16V5MX-4-GP_SMD-BCG5-SC22A"
			(at -0.0762 -8.2677 180)
			(unlocked yes)
			(layer "F.Fab")
			(hide yes)
			(effects
				(font
					(size 1.27 1.016)
					(thickness 0.1524)
				)
			)
		)
		(duplicate_pad_numbers_are_jumpers no)
		(fp_line
			(start 0.635 0)
			(end -0.635 0)
			(stroke
				(width 0.508)
				(type default)
			)
			(layer "F.SilkS")
		)
		(fp_rect
			(start -0.9652 1.778)
			(end 0.9652 -1.778)
			(stroke
				(width 0)
				(type default)
			)
			(fill no)
			(layer "F.CrtYd")
		)
		(fp_poly
			(pts
				(xy -0.9652 -1.778) (xy 0.9652 -1.778) (xy 0.9652 1.778) (xy -0.9652 1.778)
			)
			(stroke
				(width 0)
				(type default)
			)
			(fill no)
			(layer "F.Fab")
		)
		(pad "1" smd rect
			(at 0 -0.9652 180)
			(size 1.397 1.143)
			(layers "F.Cu" "F.Mask" "F.Paste")
			(net "VR_FET_SW_P5V_STBY_PVIN")
		)
		(pad "2" smd rect
			(at 0 0.9652 180)
			(size 1.397 1.143)
			(layers "F.Cu" "F.Mask" "F.Paste")
			(net "GND")
		)
	)
	(footprint ""
		(layer "F.Cu")
		(at 94.45244 -77.636116)
		(property "Reference" "C2D20"
			(at 0 0 0)
			(layer "F.SilkS")
			(hide yes)
			(effects
				(font
					(size 1.27 1.27)
				)
			)
		)
		(property "Value" ""
			(at 0 0 0)
			(layer "F.Fab")
			(effects
				(font
					(size 1.27 1.27)
				)
			)
		)
		(duplicate_pad_numbers_are_jumpers no)
		(fp_poly
			(pts
				(xy -0.4953 -0.2032) (xy 0.4953 -0.2032) (xy 0.4953 1.6002) (xy -0.4953 1.6002)
			)
			(stroke
				(width 0)
				(type default)
			)
			(fill no)
			(layer "F.CrtYd")
		)
		(fp_line
			(start -0.4953 -0.2032)
			(end 0.4953 -0.2032)
			(stroke
				(width 0.1)
				(type default)
			)
			(layer "F.Fab")
		)
		(fp_line
			(start -0.4953 1.6002)
			(end -0.4953 -0.2032)
			(stroke
				(width 0.1)
				(type default)
			)
			(layer "F.Fab")
		)
		(fp_line
			(start 0.4953 -0.2032)
			(end 0.4953 1.6002)
			(stroke
				(width 0.1)
				(type default)
			)
			(layer "F.Fab")
		)
		(fp_line
			(start 0.4953 1.6002)
			(end -0.4953 1.6002)
			(stroke
				(width 0.1)
				(type default)
			)
			(layer "F.Fab")
		)
		(pad "1" smd rect
			(at 0 0)
			(size 0.762 0.889)
			(layers "F.Cu" "F.Mask" "F.Paste")
			(net "PVCCIN_CPU1")
		)
		(pad "2" smd rect
			(at 0 1.397)
			(size 0.762 0.889)
			(layers "F.Cu" "F.Mask" "F.Paste")
			(net "GND")
		)
		(zone
			(layer "F.Cu")
			(hatch none 0.5)
			(connect_pads
				(clearance 0)
			)
			(min_thickness 0.25)
			(keepout
				(tracks not_allowed)
				(vias allowed)
				(pads allowed)
				(copperpour not_allowed)
				(footprints allowed)
			)
			(placement
				(enabled no)
				(sheetname "")
			)
			(fill
				(thermal_gap 0.5)
				(thermal_bridge_width 0.5)
				(island_removal_mode 0)
			)
			(polygon
				(pts
					(xy 94.07144 -77.191616) (xy 94.83344 -77.191616) (xy 94.83344 -76.683616) (xy 94.07144 -76.683616)
				)
			)
		)
	)
	(footprint ""
		(layer "F.Cu")
		(at 99.43084 -77.636116)
		(property "Reference" "C2D24"
			(at 0 0 0)
			(layer "F.SilkS")
			(hide yes)
			(effects
				(font
					(size 1.27 1.27)
				)
			)
		)
		(property "Value" ""
			(at 0 0 0)
			(layer "F.Fab")
			(effects
				(font
					(size 1.27 1.27)
				)
			)
		)
		(duplicate_pad_numbers_are_jumpers no)
		(fp_poly
			(pts
				(xy -0.4953 -0.2032) (xy 0.4953 -0.2032) (xy 0.4953 1.6002) (xy -0.4953 1.6002)
			)
			(stroke
				(width 0)
				(type default)
			)
			(fill no)
			(layer "F.CrtYd")
		)
		(fp_line
			(start -0.4953 -0.2032)
			(end 0.4953 -0.2032)
			(stroke
				(width 0.1)
				(type default)
			)
			(layer "F.Fab")
		)
		(fp_line
			(start -0.4953 1.6002)
			(end -0.4953 -0.2032)
			(stroke
				(width 0.1)
				(type default)
			)
			(layer "F.Fab")
		)
		(fp_line
			(start 0.4953 -0.2032)
			(end 0.4953 1.6002)
			(stroke
				(width 0.1)
				(type default)
			)
			(layer "F.Fab")
		)
		(fp_line
			(start 0.4953 1.6002)
			(end -0.4953 1.6002)
			(stroke
				(width 0.1)
				(type default)
			)
			(layer "F.Fab")
		)
		(pad "1" smd rect
			(at 0 0)
			(size 0.762 0.889)
			(layers "F.Cu" "F.Mask" "F.Paste")
			(net "PVCCIN_CPU1")
		)
		(pad "2" smd rect
			(at 0 1.397)
			(size 0.762 0.889)
			(layers "F.Cu" "F.Mask" "F.Paste")
			(net "GND")
		)
		(zone
			(layer "F.Cu")
			(hatch none 0.5)
			(connect_pads
				(clearance 0)
			)
			(min_thickness 0.25)
			(keepout
				(tracks not_allowed)
				(vias allowed)
				(pads allowed)
				(copperpour not_allowed)
				(footprints allowed)
			)
			(placement
				(enabled no)
				(sheetname "")
			)
			(fill
				(thermal_gap 0.5)
				(thermal_bridge_width 0.5)
				(island_removal_mode 0)
			)
			(polygon
				(pts
					(xy 99.04984 -77.191616) (xy 99.81184 -77.191616) (xy 99.81184 -76.683616) (xy 99.04984 -76.683616)
				)
			)
		)
	)
	(footprint ""
		(layer "F.Cu")
		(at 170.815 -70.6374 180)
		(property "Reference" "C4D31"
			(at 0 0 180)
			(layer "F.SilkS")
			(hide yes)
			(effects
				(font
					(size 1.27 1.27)
				)
			)
		)
		(property "Value" ""
			(at 0 0 180)
			(layer "F.Fab")
			(effects
				(font
					(size 1.27 1.27)
				)
			)
		)
		(duplicate_pad_numbers_are_jumpers no)
		(fp_poly
			(pts
				(xy 0.3048 -0.1016) (xy 0.3048 0.9906) (xy -0.3048 0.9906) (xy -0.3048 -0.1016)
			)
			(stroke
				(width 0)
				(type default)
			)
			(fill no)
			(layer "F.CrtYd")
		)
		(fp_line
			(start 0.3048 0.9906)
			(end 0.3048 -0.1016)
			(stroke
				(width 0.1)
				(type default)
			)
			(layer "F.Fab")
		)
		(fp_line
			(start 0.3048 -0.1016)
			(end -0.3048 -0.1016)
			(stroke
				(width 0.1)
				(type default)
			)
			(layer "F.Fab")
		)
		(fp_line
			(start -0.3048 0.9906)
			(end 0.3048 0.9906)
			(stroke
				(width 0.1)
				(type default)
			)
			(layer "F.Fab")
		)
		(fp_line
			(start -0.3048 -0.1016)
			(end -0.3048 0.9906)
			(stroke
				(width 0.1)
				(type default)
			)
			(layer "F.Fab")
		)
		(pad "1" smd rect
			(at 0 0 180)
			(size 0.508 0.508)
			(layers "F.Cu" "F.Mask" "F.Paste")
			(net "VR_PVCCIO_CPU1_VD12")
		)
		(pad "2" smd rect
			(at 0 0.889 180)
			(size 0.508 0.508)
			(layers "F.Cu" "F.Mask" "F.Paste")
			(net "GND")
		)
		(zone
			(layer "F.Cu")
			(hatch none 0.5)
			(connect_pads
				(clearance 0)
			)
			(min_thickness 0.25)
			(keepout
				(tracks not_allowed)
				(vias allowed)
				(pads allowed)
				(copperpour not_allowed)
				(footprints allowed)
			)
			(placement
				(enabled no)
				(sheetname "")
			)
			(fill
				(thermal_gap 0.5)
				(thermal_bridge_width 0.5)
				(island_removal_mode 0)
			)
			(polygon
				(pts
					(xy 171.069 -71.2724) (xy 170.561 -71.2724) (xy 170.561 -70.8914) (xy 171.069 -70.8914)
				)
			)
		)
		(zone
			(layer "F.Cu")
			(hatch none 0.5)
			(connect_pads
				(clearance 0)
			)
			(min_thickness 0.25)
			(keepout
				(tracks allowed)
				(vias not_allowed)
				(pads allowed)
				(copperpour not_allowed)
				(footprints allowed)
			)
			(placement
				(enabled no)
				(sheetname "")
			)
			(fill
				(thermal_gap 0.5)
				(thermal_bridge_width 0.5)
				(island_removal_mode 0)
			)
			(polygon
				(pts
					(xy 171.069 -70.8914) (xy 170.561 -70.8914) (xy 170.561 -71.2724) (xy 171.069 -71.2724)
				)
			)
		)
	)
	(footprint ""
		(layer "F.Cu")
		(at 390.398 -63.6905 180)
		(property "Reference" "R7F1"
			(at 0 0 180)
			(layer "F.SilkS")
			(hide yes)
			(effects
				(font
					(size 1.27 1.27)
				)
			)
		)
		(property "Value" ""
			(at 0 0 180)
			(layer "F.Fab")
			(effects
				(font
					(size 1.27 1.27)
				)
			)
		)
		(duplicate_pad_numbers_are_jumpers no)
		(fp_poly
			(pts
				(xy -0.2794 -0.1016) (xy 0.2794 -0.1016) (xy 0.2794 0.9906) (xy -0.2794 0.9906)
			)
			(stroke
				(width 0)
				(type default)
			)
			(fill no)
			(layer "F.CrtYd")
		)
		(fp_line
			(start 0.2794 0.9906)
			(end 0.2794 -0.1016)
			(stroke
				(width 0.1)
				(type default)
			)
			(layer "F.Fab")
		)
		(fp_line
			(start 0.2794 -0.1016)
			(end -0.2794 -0.1016)
			(stroke
				(width 0.1)
				(type default)
			)
			(layer "F.Fab")
		)
		(fp_line
			(start -0.2794 0.9906)
			(end 0.2794 0.9906)
			(stroke
				(width 0.1)
				(type default)
			)
			(layer "F.Fab")
		)
		(fp_line
			(start -0.2794 -0.1016)
			(end -0.2794 0.9906)
			(stroke
				(width 0.1)
				(type default)
			)
			(layer "F.Fab")
		)
		(pad "1" smd rect
			(at 0 0 180)
			(size 0.508 0.508)
			(layers "F.Cu" "F.Mask" "F.Paste")
			(net "VR_P5V_STBY_VSENSE_R")
		)
		(pad "2" smd rect
			(at 0 0.889 180)
			(size 0.508 0.508)
			(layers "F.Cu" "F.Mask" "F.Paste")
			(net "VR_P5V_STBY_VSENSE")
		)
		(zone
			(layer "F.Cu")
			(hatch none 0.5)
			(connect_pads
				(clearance 0)
			)
			(min_thickness 0.25)
			(keepout
				(tracks not_allowed)
				(vias allowed)
				(pads allowed)
				(copperpour not_allowed)
				(footprints allowed)
			)
			(placement
				(enabled no)
				(sheetname "")
			)
			(fill
				(thermal_gap 0.5)
				(thermal_bridge_width 0.5)
				(island_removal_mode 0)
			)
			(polygon
				(pts
					(xy 390.652 -64.3255) (xy 390.144 -64.3255) (xy 390.144 -63.9445) (xy 390.652 -63.9445)
				)
			)
		)
		(zone
			(layer "F.Cu")
			(hatch none 0.5)
			(connect_pads
				(clearance 0)
			)
			(min_thickness 0.25)
			(keepout
				(tracks allowed)
				(vias not_allowed)
				(pads allowed)
				(copperpour not_allowed)
				(footprints allowed)
			)
			(placement
				(enabled no)
				(sheetname "")
			)
			(fill
				(thermal_gap 0.5)
				(thermal_bridge_width 0.5)
				(island_removal_mode 0)
			)
			(polygon
				(pts
					(xy 390.652 -63.9445) (xy 390.144 -63.9445) (xy 390.144 -64.3255) (xy 390.652 -64.3255)
				)
			)
		)
	)
	(footprint ""
		(layer "F.Cu")
		(at 419.6207 -104.267 90)
		(property "Reference" "R6W26"
			(at -0.8382 -0.67818 90)
			(unlocked yes)
			(layer "F.SilkS")
			(effects
				(font
					(size 0.4064 0.254)
					(thickness 0.1524)
				)
				(justify left)
			)
		)
		(property "Value" ""
			(at 0 0 90)
			(layer "F.Fab")
			(effects
				(font
					(size 1.27 1.27)
				)
			)
		)
		(duplicate_pad_numbers_are_jumpers no)
		(fp_poly
			(pts
				(xy -0.2794 -0.1016) (xy 0.2794 -0.1016) (xy 0.2794 0.9906) (xy -0.2794 0.9906)
			)
			(stroke
				(width 0)
				(type default)
			)
			(fill no)
			(layer "F.CrtYd")
		)
		(fp_line
			(start 0.2794 -0.1016)
			(end -0.2794 -0.1016)
			(stroke
				(width 0.1)
				(type default)
			)
			(layer "F.Fab")
		)
		(fp_line
			(start -0.2794 -0.1016)
			(end -0.2794 0.9906)
			(stroke
				(width 0.1)
				(type default)
			)
			(layer "F.Fab")
		)
		(fp_line
			(start 0.2794 0.9906)
			(end 0.2794 -0.1016)
			(stroke
				(width 0.1)
				(type default)
			)
			(layer "F.Fab")
		)
		(fp_line
			(start -0.2794 0.9906)
			(end 0.2794 0.9906)
			(stroke
				(width 0.1)
				(type default)
			)
			(layer "F.Fab")
		)
		(pad "1" smd rect
			(at 0 0 90)
			(size 0.508 0.508)
			(layers "F.Cu" "F.Mask" "F.Paste")
			(net "SMB_CPU0_PE_HP_GTL_SCL")
		)
		(pad "2" smd rect
			(at 0 0.889 90)
			(size 0.508 0.508)
			(layers "F.Cu" "F.Mask" "F.Paste")
			(net "SMB_CPU0_PE_HP_GTL_R_SCL")
		)
		(zone
			(layer "F.Cu")
			(hatch none 0.5)
			(connect_pads
				(clearance 0)
			)
			(min_thickness 0.25)
			(keepout
				(tracks allowed)
				(vias not_allowed)
				(pads allowed)
				(copperpour not_allowed)
				(footprints allowed)
			)
			(placement
				(enabled no)
				(sheetname "")
			)
			(fill
				(thermal_gap 0.5)
				(thermal_bridge_width 0.5)
				(island_removal_mode 0)
			)
			(polygon
				(pts
					(xy 419.8747 -104.013) (xy 419.8747 -104.521) (xy 420.2557 -104.521) (xy 420.2557 -104.013)
				)
			)
		)
		(zone
			(layer "F.Cu")
			(hatch none 0.5)
			(connect_pads
				(clearance 0)
			)
			(min_thickness 0.25)
			(keepout
				(tracks not_allowed)
				(vias allowed)
				(pads allowed)
				(copperpour not_allowed)
				(footprints allowed)
			)
			(placement
				(enabled no)
				(sheetname "")
			)
			(fill
				(thermal_gap 0.5)
				(thermal_bridge_width 0.5)
				(island_removal_mode 0)
			)
			(polygon
				(pts
					(xy 420.2557 -104.013) (xy 420.2557 -104.521) (xy 419.8747 -104.521) (xy 419.8747 -104.013)
				)
			)
		)
	)
)
